FILE_TYPE = MACRO_DRAWING;
SET COLOR_WIRE YELLOW;
SET COLOR_PROP ORANGE;
SET COLOR_DOT WHITE;
SET COLOR_ARC YELLOW;
SET COLOR_BODY GREEN;
SET COLOR_NOTE PURPLE;
SET PROP_DISPLAY VALUE;
SET PAGE_NUMBER P426;
FORCEADD PT5161LRS..8
(-7825 4175);
FORCEPROP 1 LAST LOCATION U6013
J 0
(-8175 5800);
DISPLAY 0.723404 (-8175 5800);
PAINT GREEN (-8175 5800);
FORCEPROP 0 LAST $SEC 8
J 0
(-8175 5950);
DISPLAY 0.680851 (-8175 5950);
PAINT MONO (-8175 5950);
DISPLAY INVISIBLE (-8175 5950);
FORCEPROP 0 LAST CDS_SEC 8
J 0
(-8175 5950);
DISPLAY 0.680851 (-8175 5950);
DISPLAY INVISIBLE (-8175 5950);
FORCEPROP 0 LASTPIN (-7375 5325) $PN R35
J 0
(-7365 5335);
DISPLAY 0.680851 (-7365 5335);
PAINT MONO (-7365 5335);
FORCEPROP 0 LASTPIN (-7375 4975) $PN AB35
J 0
(-7365 4985);
DISPLAY 0.680851 (-7365 4985);
PAINT MONO (-7365 4985);
FORCEPROP 0 LASTPIN (-7375 4625) $PN AJ35
J 0
(-7365 4635);
DISPLAY 0.680851 (-7365 4635);
PAINT MONO (-7365 4635);
FORCEPROP 0 LASTPIN (-7375 4275) $PN AT35
J 0
(-7365 4285);
DISPLAY 0.680851 (-7365 4285);
PAINT MONO (-7365 4285);
FORCEPROP 0 LASTPIN (-7375 3925) $PN BC35
J 0
(-7365 3935);
DISPLAY 0.680851 (-7365 3935);
PAINT MONO (-7365 3935);
FORCEPROP 0 LASTPIN (-7375 3575) $PN BK35
J 0
(-7365 3585);
DISPLAY 0.680851 (-7365 3585);
PAINT MONO (-7365 3585);
FORCEPROP 0 LASTPIN (-7375 3225) $PN BU35
J 0
(-7365 3235);
DISPLAY 0.680851 (-7365 3235);
PAINT MONO (-7365 3235);
FORCEPROP 0 LASTPIN (-7375 2875) $PN CD35
J 0
(-7365 2885);
DISPLAY 0.680851 (-7365 2885);
PAINT MONO (-7365 2885);
FORCEPROP 0 LASTPIN (-7375 5425) $PN N34
J 0
(-7365 5435);
DISPLAY 0.680851 (-7365 5435);
PAINT MONO (-7365 5435);
FORCEPROP 0 LASTPIN (-7375 5075) $PN Y34
J 0
(-7365 5085);
DISPLAY 0.680851 (-7365 5085);
PAINT MONO (-7365 5085);
FORCEPROP 0 LASTPIN (-7375 4725) $PN AG34
J 0
(-7365 4735);
DISPLAY 0.680851 (-7365 4735);
PAINT MONO (-7365 4735);
FORCEPROP 0 LASTPIN (-7375 4375) $PN AP34
J 0
(-7365 4385);
DISPLAY 0.680851 (-7365 4385);
PAINT MONO (-7365 4385);
FORCEPROP 0 LASTPIN (-7375 4025) $PN BA34
J 0
(-7365 4035);
DISPLAY 0.680851 (-7365 4035);
PAINT MONO (-7365 4035);
FORCEPROP 0 LASTPIN (-7375 3675) $PN BH34
J 0
(-7365 3685);
DISPLAY 0.680851 (-7365 3685);
PAINT MONO (-7365 3685);
FORCEPROP 0 LASTPIN (-7375 3325) $PN BR34
J 0
(-7365 3335);
DISPLAY 0.680851 (-7365 3335);
PAINT MONO (-7365 3335);
FORCEPROP 0 LASTPIN (-7375 2975) $PN CB34
J 0
(-7365 2985);
DISPLAY 0.680851 (-7365 2985);
PAINT MONO (-7365 2985);
FORCEPROP 1 LAST MATERIAL IC
J 0
(-8175 5650);
DISPLAY 0.723404 (-8175 5650);
PAINT GREEN (-8175 5650);
FORCEPROP 2 LAST VALUE PT5161LRS
J 0
(-8175 5850);
DISPLAY 0.680851 (-8175 5850);
FORCEPROP 2 LAST PART_TYPE SMLF
J 0
(-8175 5900);
DISPLAY 0.680851 (-8175 5900);
FORCEPROP 1 LAST NEEDS_NO_SIZE TRUE
J 0
(-7825 4175);
DISPLAY 0.723404 (-7825 4175);
PAINT GREEN (-7825 4175);
DISPLAY INVISIBLE (-7825 4175);
FORCEPROP 1 LAST CDS_LMAN_SYM_OUTLINE -350,1450,300,-1400
J 0
(-7825 4175);
DISPLAY 0.468085 (-7825 4175);
PAINT GREEN (-7825 4175);
DISPLAY INVISIBLE (-7825 4175);
FORCEPROP 2 LAST CDS_LIB pure_quanta
J 0
(-7825 4175);
DISPLAY INVISIBLE (-7825 4175);
FORCEPROP 1 LAST PATH I1
J 0
(-7825 4175);
DISPLAY 0.723404 (-7825 4175);
PAINT GREEN (-7825 4175);
DISPLAY INVISIBLE (-7825 4175);
FORCEPROP 1 LAST PART_NUMBER AJ051610U03
J 0
(-8175 5725);
DISPLAY 0.723404 (-8175 5725);
PAINT GREEN (-8175 5725);
DISPLAY INVISIBLE (-8175 5725);
FORCEADD TAP..1
(-6800 4375);
FORCEPROP 3 LASTPIN (-6850 4375) SIG_NAME P5E_CPU0_P3_TX_C_DN<12>
J 0
(-6840 4385);
DISPLAY 0.659574 (-6840 4385);
PAINT MONO (-6840 4385);
DISPLAY INVISIBLE (-6840 4385);
FORCEPROP 1 LASTPIN (-6850 4375) BN 12
J 0
(-6862 4383);
DISPLAY 0.680851 (-6862 4383);
PAINT GREEN (-6862 4383);
FORCEPROP 2 LAST CDS_LIB standard
J 0
(-6800 4375);
DISPLAY INVISIBLE (-6800 4375);
FORCEPROP 1 LAST BODY_TYPE PLUMBING
J 0
(-6800 4425);
DISPLAY 0.872340 (-6800 4425);
PAINT GREEN (-6800 4425);
DISPLAY INVISIBLE (-6800 4425);
FORCEPROP 1 LAST HDL_TAP TRUE
J 0
(-6475 4250);
DISPLAY 0.872340 (-6475 4250);
DISPLAY INVISIBLE (-6475 4250);
FORCEPROP 1 LAST PATH I10
J 0
(-6802 4375);
DISPLAY 0.872340 (-6802 4375);
PAINT GREEN (-6802 4375);
DISPLAY INVISIBLE (-6802 4375);
FORCEADD TAP..1
(-6600 4275);
FORCEPROP 3 LASTPIN (-6650 4275) SIG_NAME P5E_CPU0_P3_TX_C_DP<12>
J 0
(-6640 4285);
DISPLAY 0.659574 (-6640 4285);
PAINT MONO (-6640 4285);
DISPLAY INVISIBLE (-6640 4285);
FORCEPROP 1 LASTPIN (-6650 4275) BN 12
J 0
(-6662 4283);
DISPLAY 0.680851 (-6662 4283);
PAINT GREEN (-6662 4283);
FORCEPROP 2 LAST CDS_LIB standard
J 0
(-6600 4275);
DISPLAY INVISIBLE (-6600 4275);
FORCEPROP 1 LAST BODY_TYPE PLUMBING
J 0
(-6600 4325);
DISPLAY 0.872340 (-6600 4325);
PAINT GREEN (-6600 4325);
DISPLAY INVISIBLE (-6600 4325);
FORCEPROP 1 LAST HDL_TAP TRUE
J 0
(-6275 4150);
DISPLAY 0.872340 (-6275 4150);
DISPLAY INVISIBLE (-6275 4150);
FORCEPROP 1 LAST PATH I11
J 0
(-6602 4275);
DISPLAY 0.872340 (-6602 4275);
PAINT GREEN (-6602 4275);
DISPLAY INVISIBLE (-6602 4275);
FORCEADD TAP..1
(-6800 4725);
FORCEPROP 3 LASTPIN (-6850 4725) SIG_NAME P5E_CPU0_P3_TX_C_DN<13>
J 0
(-6840 4735);
DISPLAY 0.659574 (-6840 4735);
PAINT MONO (-6840 4735);
DISPLAY INVISIBLE (-6840 4735);
FORCEPROP 1 LASTPIN (-6850 4725) BN 13
J 0
(-6862 4733);
DISPLAY 0.680851 (-6862 4733);
PAINT GREEN (-6862 4733);
FORCEPROP 2 LAST CDS_LIB standard
J 0
(-6800 4725);
DISPLAY INVISIBLE (-6800 4725);
FORCEPROP 1 LAST BODY_TYPE PLUMBING
J 0
(-6800 4775);
DISPLAY 0.872340 (-6800 4775);
PAINT GREEN (-6800 4775);
DISPLAY INVISIBLE (-6800 4775);
FORCEPROP 1 LAST HDL_TAP TRUE
J 0
(-6475 4600);
DISPLAY 0.872340 (-6475 4600);
DISPLAY INVISIBLE (-6475 4600);
FORCEPROP 1 LAST PATH I12
J 0
(-6802 4725);
DISPLAY 0.872340 (-6802 4725);
PAINT GREEN (-6802 4725);
DISPLAY INVISIBLE (-6802 4725);
FORCEADD TAP..1
(-6600 4625);
FORCEPROP 3 LASTPIN (-6650 4625) SIG_NAME P5E_CPU0_P3_TX_C_DP<13>
J 0
(-6640 4635);
DISPLAY 0.659574 (-6640 4635);
PAINT MONO (-6640 4635);
DISPLAY INVISIBLE (-6640 4635);
FORCEPROP 1 LASTPIN (-6650 4625) BN 13
J 0
(-6662 4633);
DISPLAY 0.680851 (-6662 4633);
PAINT GREEN (-6662 4633);
FORCEPROP 2 LAST CDS_LIB standard
J 0
(-6600 4625);
DISPLAY INVISIBLE (-6600 4625);
FORCEPROP 1 LAST BODY_TYPE PLUMBING
J 0
(-6600 4675);
DISPLAY 0.872340 (-6600 4675);
PAINT GREEN (-6600 4675);
DISPLAY INVISIBLE (-6600 4675);
FORCEPROP 1 LAST HDL_TAP TRUE
J 0
(-6275 4500);
DISPLAY 0.872340 (-6275 4500);
DISPLAY INVISIBLE (-6275 4500);
FORCEPROP 1 LAST PATH I13
J 0
(-6602 4625);
DISPLAY 0.872340 (-6602 4625);
PAINT GREEN (-6602 4625);
DISPLAY INVISIBLE (-6602 4625);
FORCEADD TAP..1
(-6800 4975);
FORCEPROP 3 LASTPIN (-6850 4975) SIG_NAME P5E_CPU0_P3_TX_C_DN<14>
J 0
(-6840 4985);
DISPLAY 0.659574 (-6840 4985);
PAINT MONO (-6840 4985);
DISPLAY INVISIBLE (-6840 4985);
FORCEPROP 1 LASTPIN (-6850 4975) BN 14
J 0
(-6862 4983);
DISPLAY 0.680851 (-6862 4983);
PAINT GREEN (-6862 4983);
FORCEPROP 2 LAST CDS_LIB standard
J 0
(-6800 4975);
DISPLAY INVISIBLE (-6800 4975);
FORCEPROP 1 LAST BODY_TYPE PLUMBING
J 0
(-6800 5025);
DISPLAY 0.872340 (-6800 5025);
PAINT GREEN (-6800 5025);
DISPLAY INVISIBLE (-6800 5025);
FORCEPROP 1 LAST HDL_TAP TRUE
J 0
(-6475 4850);
DISPLAY 0.872340 (-6475 4850);
DISPLAY INVISIBLE (-6475 4850);
FORCEPROP 1 LAST PATH I14
J 0
(-6802 4975);
DISPLAY 0.872340 (-6802 4975);
PAINT GREEN (-6802 4975);
DISPLAY INVISIBLE (-6802 4975);
FORCEADD TAP..1
(-6800 5425);
FORCEPROP 3 LASTPIN (-6850 5425) SIG_NAME P5E_CPU0_P3_TX_C_DN<15>
J 0
(-6840 5435);
DISPLAY 0.659574 (-6840 5435);
PAINT MONO (-6840 5435);
DISPLAY INVISIBLE (-6840 5435);
FORCEPROP 1 LASTPIN (-6850 5425) BN 15
J 0
(-6862 5433);
DISPLAY 0.680851 (-6862 5433);
PAINT GREEN (-6862 5433);
FORCEPROP 2 LAST CDS_LIB standard
J 0
(-6800 5425);
DISPLAY INVISIBLE (-6800 5425);
FORCEPROP 1 LAST BODY_TYPE PLUMBING
J 0
(-6800 5475);
DISPLAY 0.872340 (-6800 5475);
PAINT GREEN (-6800 5475);
DISPLAY INVISIBLE (-6800 5475);
FORCEPROP 1 LAST HDL_TAP TRUE
J 0
(-6475 5300);
DISPLAY 0.872340 (-6475 5300);
DISPLAY INVISIBLE (-6475 5300);
FORCEPROP 1 LAST PATH I15
J 0
(-6802 5425);
DISPLAY 0.872340 (-6802 5425);
PAINT GREEN (-6802 5425);
DISPLAY INVISIBLE (-6802 5425);
FORCEADD TAP..1
(-6600 5075);
FORCEPROP 3 LASTPIN (-6650 5075) SIG_NAME P5E_CPU0_P3_TX_C_DP<14>
J 0
(-6640 5085);
DISPLAY 0.659574 (-6640 5085);
PAINT MONO (-6640 5085);
DISPLAY INVISIBLE (-6640 5085);
FORCEPROP 1 LASTPIN (-6650 5075) BN 14
J 0
(-6662 5083);
DISPLAY 0.680851 (-6662 5083);
PAINT GREEN (-6662 5083);
FORCEPROP 2 LAST CDS_LIB standard
J 0
(-6600 5075);
DISPLAY INVISIBLE (-6600 5075);
FORCEPROP 1 LAST BODY_TYPE PLUMBING
J 0
(-6600 5125);
DISPLAY 0.872340 (-6600 5125);
PAINT GREEN (-6600 5125);
DISPLAY INVISIBLE (-6600 5125);
FORCEPROP 1 LAST HDL_TAP TRUE
J 0
(-6275 4950);
DISPLAY 0.872340 (-6275 4950);
DISPLAY INVISIBLE (-6275 4950);
FORCEPROP 1 LAST PATH I16
J 0
(-6602 5075);
DISPLAY 0.872340 (-6602 5075);
PAINT GREEN (-6602 5075);
DISPLAY INVISIBLE (-6602 5075);
FORCEADD TAP..1
(-6600 5325);
FORCEPROP 3 LASTPIN (-6650 5325) SIG_NAME P5E_CPU0_P3_TX_C_DP<15>
J 0
(-6640 5335);
DISPLAY 0.659574 (-6640 5335);
PAINT MONO (-6640 5335);
DISPLAY INVISIBLE (-6640 5335);
FORCEPROP 1 LASTPIN (-6650 5325) BN 15
J 0
(-6662 5333);
DISPLAY 0.680851 (-6662 5333);
PAINT GREEN (-6662 5333);
FORCEPROP 2 LAST CDS_LIB standard
J 0
(-6600 5325);
DISPLAY INVISIBLE (-6600 5325);
FORCEPROP 1 LAST BODY_TYPE PLUMBING
J 0
(-6600 5375);
DISPLAY 0.872340 (-6600 5375);
PAINT GREEN (-6600 5375);
DISPLAY INVISIBLE (-6600 5375);
FORCEPROP 1 LAST HDL_TAP TRUE
J 0
(-6275 5200);
DISPLAY 0.872340 (-6275 5200);
DISPLAY INVISIBLE (-6275 5200);
FORCEPROP 1 LAST PATH I17
J 0
(-6602 5325);
DISPLAY 0.872340 (-6602 5325);
PAINT GREEN (-6602 5325);
DISPLAY INVISIBLE (-6602 5325);
FORCEADD OFFPAGE..1
R 2
(-5600 5450);
FORCEPROP 2 LAST $XR0 64 
J 0
(-5414 5450);
DISPLAY 0.638298 (-5414 5450);
PAINT MONO (-5414 5450);
FORCEPROP 2 LAST CDS_LIB standard
J 2
(-5600 5450);
DISPLAY INVISIBLE (-5600 5450);
FORCEPROP 1 LAST OFFPAGE TRUE
J 2
(-5925 5325);
DISPLAY 0.872340 (-5925 5325);
DISPLAY INVISIBLE (-5925 5325);
FORCEPROP 1 LAST COMMENT_BODY TRUE
J 2
(-5725 5350);
DISPLAY 0.872340 (-5725 5350);
PAINT GREEN (-5725 5350);
DISPLAY INVISIBLE (-5725 5350);
FORCEPROP 2 LAST PATH I18
J 0
(-5425 5525);
DISPLAY 0.680851 (-5425 5525);
DISPLAY INVISIBLE (-5425 5525);
FORCEADD OFFPAGE..1
R 2
(-5600 5350);
FORCEPROP 2 LAST $XR0 64 
J 0
(-5414 5350);
DISPLAY 0.638298 (-5414 5350);
PAINT MONO (-5414 5350);
FORCEPROP 2 LAST CDS_LIB standard
J 0
(-5600 5350);
DISPLAY INVISIBLE (-5600 5350);
FORCEPROP 1 LAST OFFPAGE TRUE
J 2
(-5925 5225);
DISPLAY 0.872340 (-5925 5225);
DISPLAY INVISIBLE (-5925 5225);
FORCEPROP 1 LAST COMMENT_BODY TRUE
J 2
(-5725 5250);
DISPLAY 0.872340 (-5725 5250);
PAINT GREEN (-5725 5250);
DISPLAY INVISIBLE (-5725 5250);
FORCEPROP 2 LAST PATH I19
J 0
(-5425 5425);
DISPLAY 0.680851 (-5425 5425);
DISPLAY INVISIBLE (-5425 5425);
FORCEADD TAP..1
(-6600 2875);
FORCEPROP 3 LASTPIN (-6650 2875) SIG_NAME P5E_CPU0_P3_TX_C_DP<8>
J 0
(-6640 2885);
DISPLAY 0.659574 (-6640 2885);
PAINT MONO (-6640 2885);
DISPLAY INVISIBLE (-6640 2885);
FORCEPROP 1 LASTPIN (-6650 2875) BN 8
J 0
(-6662 2883);
DISPLAY 0.680851 (-6662 2883);
PAINT GREEN (-6662 2883);
FORCEPROP 2 LAST CDS_LIB standard
J 0
(-6600 2875);
DISPLAY INVISIBLE (-6600 2875);
FORCEPROP 1 LAST BODY_TYPE PLUMBING
J 0
(-6600 2925);
DISPLAY 0.872340 (-6600 2925);
PAINT GREEN (-6600 2925);
DISPLAY INVISIBLE (-6600 2925);
FORCEPROP 1 LAST HDL_TAP TRUE
J 0
(-6275 2750);
DISPLAY 0.872340 (-6275 2750);
DISPLAY INVISIBLE (-6275 2750);
FORCEPROP 1 LAST PATH I2
J 0
(-6602 2875);
DISPLAY 0.872340 (-6602 2875);
PAINT GREEN (-6602 2875);
DISPLAY INVISIBLE (-6602 2875);
FORCEADD TAP..1
(-2175 3175);
FORCEPROP 3 LASTPIN (-2225 3175) SIG_NAME P5E_CPU0_P3_TX_C_DN<1>
J 0
(-2215 3185);
DISPLAY 0.659574 (-2215 3185);
PAINT MONO (-2215 3185);
DISPLAY INVISIBLE (-2215 3185);
FORCEPROP 1 LASTPIN (-2225 3175) BN 1
J 0
(-2237 3183);
DISPLAY 0.680851 (-2237 3183);
PAINT GREEN (-2237 3183);
FORCEPROP 2 LAST CDS_LIB standard
J 0
(-2175 3175);
DISPLAY INVISIBLE (-2175 3175);
FORCEPROP 1 LAST BODY_TYPE PLUMBING
J 0
(-2175 3225);
DISPLAY 0.872340 (-2175 3225);
PAINT GREEN (-2175 3225);
DISPLAY INVISIBLE (-2175 3225);
FORCEPROP 1 LAST HDL_TAP TRUE
J 0
(-1850 3050);
DISPLAY 0.872340 (-1850 3050);
DISPLAY INVISIBLE (-1850 3050);
FORCEPROP 1 LAST PATH I20
J 0
(-2177 3175);
DISPLAY 0.872340 (-2177 3175);
PAINT GREEN (-2177 3175);
DISPLAY INVISIBLE (-2177 3175);
FORCEADD TAP..1
(-1975 3275);
FORCEPROP 3 LASTPIN (-2025 3275) SIG_NAME P5E_CPU0_P3_TX_C_DP<1>
J 0
(-2015 3285);
DISPLAY 0.659574 (-2015 3285);
PAINT MONO (-2015 3285);
DISPLAY INVISIBLE (-2015 3285);
FORCEPROP 1 LASTPIN (-2025 3275) BN 1
J 0
(-2037 3283);
DISPLAY 0.680851 (-2037 3283);
PAINT GREEN (-2037 3283);
FORCEPROP 2 LAST CDS_LIB standard
J 0
(-1975 3275);
DISPLAY INVISIBLE (-1975 3275);
FORCEPROP 1 LAST BODY_TYPE PLUMBING
J 0
(-1975 3325);
DISPLAY 0.872340 (-1975 3325);
PAINT GREEN (-1975 3325);
DISPLAY INVISIBLE (-1975 3325);
FORCEPROP 1 LAST HDL_TAP TRUE
J 0
(-1650 3150);
DISPLAY 0.872340 (-1650 3150);
DISPLAY INVISIBLE (-1650 3150);
FORCEPROP 1 LAST PATH I21
J 0
(-1977 3275);
DISPLAY 0.872340 (-1977 3275);
PAINT GREEN (-1977 3275);
DISPLAY INVISIBLE (-1977 3275);
FORCEADD TAP..1
(-2175 3625);
FORCEPROP 3 LASTPIN (-2225 3625) SIG_NAME P5E_CPU0_P3_TX_C_DN<2>
J 0
(-2215 3635);
DISPLAY 0.659574 (-2215 3635);
PAINT MONO (-2215 3635);
DISPLAY INVISIBLE (-2215 3635);
FORCEPROP 1 LASTPIN (-2225 3625) BN 2
J 0
(-2237 3633);
DISPLAY 0.680851 (-2237 3633);
PAINT GREEN (-2237 3633);
FORCEPROP 2 LAST CDS_LIB standard
J 0
(-2175 3625);
DISPLAY INVISIBLE (-2175 3625);
FORCEPROP 1 LAST BODY_TYPE PLUMBING
J 0
(-2175 3675);
DISPLAY 0.872340 (-2175 3675);
PAINT GREEN (-2175 3675);
DISPLAY INVISIBLE (-2175 3675);
FORCEPROP 1 LAST HDL_TAP TRUE
J 0
(-1850 3500);
DISPLAY 0.872340 (-1850 3500);
DISPLAY INVISIBLE (-1850 3500);
FORCEPROP 1 LAST PATH I22
J 0
(-2177 3625);
DISPLAY 0.872340 (-2177 3625);
PAINT GREEN (-2177 3625);
DISPLAY INVISIBLE (-2177 3625);
FORCEADD TAP..1
(-1975 3525);
FORCEPROP 3 LASTPIN (-2025 3525) SIG_NAME P5E_CPU0_P3_TX_C_DP<2>
J 0
(-2015 3535);
DISPLAY 0.659574 (-2015 3535);
PAINT MONO (-2015 3535);
DISPLAY INVISIBLE (-2015 3535);
FORCEPROP 1 LASTPIN (-2025 3525) BN 2
J 0
(-2037 3533);
DISPLAY 0.680851 (-2037 3533);
PAINT GREEN (-2037 3533);
FORCEPROP 2 LAST CDS_LIB standard
J 0
(-1975 3525);
DISPLAY INVISIBLE (-1975 3525);
FORCEPROP 1 LAST BODY_TYPE PLUMBING
J 0
(-1975 3575);
DISPLAY 0.872340 (-1975 3575);
PAINT GREEN (-1975 3575);
DISPLAY INVISIBLE (-1975 3575);
FORCEPROP 1 LAST HDL_TAP TRUE
J 0
(-1650 3400);
DISPLAY 0.872340 (-1650 3400);
DISPLAY INVISIBLE (-1650 3400);
FORCEPROP 1 LAST PATH I23
J 0
(-1977 3525);
DISPLAY 0.872340 (-1977 3525);
PAINT GREEN (-1977 3525);
DISPLAY INVISIBLE (-1977 3525);
FORCEADD TAP..1
(-1975 3875);
FORCEPROP 3 LASTPIN (-2025 3875) SIG_NAME P5E_CPU0_P3_TX_C_DP<3>
J 0
(-2015 3885);
DISPLAY 0.659574 (-2015 3885);
PAINT MONO (-2015 3885);
DISPLAY INVISIBLE (-2015 3885);
FORCEPROP 1 LASTPIN (-2025 3875) BN 3
J 0
(-2037 3883);
DISPLAY 0.680851 (-2037 3883);
PAINT GREEN (-2037 3883);
FORCEPROP 2 LAST CDS_LIB standard
J 0
(-1975 3875);
DISPLAY INVISIBLE (-1975 3875);
FORCEPROP 1 LAST BODY_TYPE PLUMBING
J 0
(-1975 3925);
DISPLAY 0.872340 (-1975 3925);
PAINT GREEN (-1975 3925);
DISPLAY INVISIBLE (-1975 3925);
FORCEPROP 1 LAST HDL_TAP TRUE
J 0
(-1650 3750);
DISPLAY 0.872340 (-1650 3750);
DISPLAY INVISIBLE (-1650 3750);
FORCEPROP 1 LAST PATH I24
J 0
(-1977 3875);
DISPLAY 0.872340 (-1977 3875);
PAINT GREEN (-1977 3875);
DISPLAY INVISIBLE (-1977 3875);
FORCEADD TAP..1
(-2175 3975);
FORCEPROP 3 LASTPIN (-2225 3975) SIG_NAME P5E_CPU0_P3_TX_C_DN<3>
J 0
(-2215 3985);
DISPLAY 0.659574 (-2215 3985);
PAINT MONO (-2215 3985);
DISPLAY INVISIBLE (-2215 3985);
FORCEPROP 1 LASTPIN (-2225 3975) BN 3
J 0
(-2237 3983);
DISPLAY 0.680851 (-2237 3983);
PAINT GREEN (-2237 3983);
FORCEPROP 2 LAST CDS_LIB standard
J 0
(-2175 3975);
DISPLAY INVISIBLE (-2175 3975);
FORCEPROP 1 LAST BODY_TYPE PLUMBING
J 0
(-2175 4025);
DISPLAY 0.872340 (-2175 4025);
PAINT GREEN (-2175 4025);
DISPLAY INVISIBLE (-2175 4025);
FORCEPROP 1 LAST HDL_TAP TRUE
J 0
(-1850 3850);
DISPLAY 0.872340 (-1850 3850);
DISPLAY INVISIBLE (-1850 3850);
FORCEPROP 1 LAST PATH I25
J 0
(-2177 3975);
DISPLAY 0.872340 (-2177 3975);
PAINT GREEN (-2177 3975);
DISPLAY INVISIBLE (-2177 3975);
FORCEADD TAP..1
(-2175 4325);
FORCEPROP 3 LASTPIN (-2225 4325) SIG_NAME P5E_CPU0_P3_TX_C_DN<4>
J 0
(-2215 4335);
DISPLAY 0.659574 (-2215 4335);
PAINT MONO (-2215 4335);
DISPLAY INVISIBLE (-2215 4335);
FORCEPROP 1 LASTPIN (-2225 4325) BN 4
J 0
(-2237 4333);
DISPLAY 0.680851 (-2237 4333);
PAINT GREEN (-2237 4333);
FORCEPROP 2 LAST CDS_LIB standard
J 0
(-2175 4325);
DISPLAY INVISIBLE (-2175 4325);
FORCEPROP 1 LAST BODY_TYPE PLUMBING
J 0
(-2175 4375);
DISPLAY 0.872340 (-2175 4375);
PAINT GREEN (-2175 4375);
DISPLAY INVISIBLE (-2175 4375);
FORCEPROP 1 LAST HDL_TAP TRUE
J 0
(-1850 4200);
DISPLAY 0.872340 (-1850 4200);
DISPLAY INVISIBLE (-1850 4200);
FORCEPROP 1 LAST PATH I26
J 0
(-2177 4325);
DISPLAY 0.872340 (-2177 4325);
PAINT GREEN (-2177 4325);
DISPLAY INVISIBLE (-2177 4325);
FORCEADD TAP..1
(-1975 4225);
FORCEPROP 3 LASTPIN (-2025 4225) SIG_NAME P5E_CPU0_P3_TX_C_DP<4>
J 0
(-2015 4235);
DISPLAY 0.659574 (-2015 4235);
PAINT MONO (-2015 4235);
DISPLAY INVISIBLE (-2015 4235);
FORCEPROP 1 LASTPIN (-2025 4225) BN 4
J 0
(-2037 4233);
DISPLAY 0.680851 (-2037 4233);
PAINT GREEN (-2037 4233);
FORCEPROP 2 LAST CDS_LIB standard
J 0
(-1975 4225);
DISPLAY INVISIBLE (-1975 4225);
FORCEPROP 1 LAST BODY_TYPE PLUMBING
J 0
(-1975 4275);
DISPLAY 0.872340 (-1975 4275);
PAINT GREEN (-1975 4275);
DISPLAY INVISIBLE (-1975 4275);
FORCEPROP 1 LAST HDL_TAP TRUE
J 0
(-1650 4100);
DISPLAY 0.872340 (-1650 4100);
DISPLAY INVISIBLE (-1650 4100);
FORCEPROP 1 LAST PATH I27
J 0
(-1977 4225);
DISPLAY 0.872340 (-1977 4225);
PAINT GREEN (-1977 4225);
DISPLAY INVISIBLE (-1977 4225);
FORCEADD TAP..1
(-2175 4675);
FORCEPROP 3 LASTPIN (-2225 4675) SIG_NAME P5E_CPU0_P3_TX_C_DN<5>
J 0
(-2215 4685);
DISPLAY 0.659574 (-2215 4685);
PAINT MONO (-2215 4685);
DISPLAY INVISIBLE (-2215 4685);
FORCEPROP 1 LASTPIN (-2225 4675) BN 5
J 0
(-2237 4683);
DISPLAY 0.680851 (-2237 4683);
PAINT GREEN (-2237 4683);
FORCEPROP 2 LAST CDS_LIB standard
J 0
(-2175 4675);
DISPLAY INVISIBLE (-2175 4675);
FORCEPROP 1 LAST BODY_TYPE PLUMBING
J 0
(-2175 4725);
DISPLAY 0.872340 (-2175 4725);
PAINT GREEN (-2175 4725);
DISPLAY INVISIBLE (-2175 4725);
FORCEPROP 1 LAST HDL_TAP TRUE
J 0
(-1850 4550);
DISPLAY 0.872340 (-1850 4550);
DISPLAY INVISIBLE (-1850 4550);
FORCEPROP 1 LAST PATH I28
J 0
(-2177 4675);
DISPLAY 0.872340 (-2177 4675);
PAINT GREEN (-2177 4675);
DISPLAY INVISIBLE (-2177 4675);
FORCEADD TAP..1
(-1975 4575);
FORCEPROP 3 LASTPIN (-2025 4575) SIG_NAME P5E_CPU0_P3_TX_C_DP<5>
J 0
(-2015 4585);
DISPLAY 0.659574 (-2015 4585);
PAINT MONO (-2015 4585);
DISPLAY INVISIBLE (-2015 4585);
FORCEPROP 1 LASTPIN (-2025 4575) BN 5
J 0
(-2037 4583);
DISPLAY 0.680851 (-2037 4583);
PAINT GREEN (-2037 4583);
FORCEPROP 2 LAST CDS_LIB standard
J 0
(-1975 4575);
DISPLAY INVISIBLE (-1975 4575);
FORCEPROP 1 LAST BODY_TYPE PLUMBING
J 0
(-1975 4625);
DISPLAY 0.872340 (-1975 4625);
PAINT GREEN (-1975 4625);
DISPLAY INVISIBLE (-1975 4625);
FORCEPROP 1 LAST HDL_TAP TRUE
J 0
(-1650 4450);
DISPLAY 0.872340 (-1650 4450);
DISPLAY INVISIBLE (-1650 4450);
FORCEPROP 1 LAST PATH I29
J 0
(-1977 4575);
DISPLAY 0.872340 (-1977 4575);
PAINT GREEN (-1977 4575);
DISPLAY INVISIBLE (-1977 4575);
FORCEADD TAP..1
(-6800 2975);
FORCEPROP 3 LASTPIN (-6850 2975) SIG_NAME P5E_CPU0_P3_TX_C_DN<8>
J 0
(-6840 2985);
DISPLAY 0.659574 (-6840 2985);
PAINT MONO (-6840 2985);
DISPLAY INVISIBLE (-6840 2985);
FORCEPROP 1 LASTPIN (-6850 2975) BN 8
J 0
(-6862 2983);
DISPLAY 0.680851 (-6862 2983);
PAINT GREEN (-6862 2983);
FORCEPROP 2 LAST CDS_LIB standard
J 0
(-6800 2975);
DISPLAY INVISIBLE (-6800 2975);
FORCEPROP 1 LAST BODY_TYPE PLUMBING
J 0
(-6800 3025);
DISPLAY 0.872340 (-6800 3025);
PAINT GREEN (-6800 3025);
DISPLAY INVISIBLE (-6800 3025);
FORCEPROP 1 LAST HDL_TAP TRUE
J 0
(-6475 2850);
DISPLAY 0.872340 (-6475 2850);
DISPLAY INVISIBLE (-6475 2850);
FORCEPROP 1 LAST PATH I3
J 0
(-6802 2975);
DISPLAY 0.872340 (-6802 2975);
PAINT GREEN (-6802 2975);
DISPLAY INVISIBLE (-6802 2975);
FORCEADD TAP..1
(-1975 4925);
FORCEPROP 3 LASTPIN (-2025 4925) SIG_NAME P5E_CPU0_P3_TX_C_DP<6>
J 0
(-2015 4935);
DISPLAY 0.659574 (-2015 4935);
PAINT MONO (-2015 4935);
DISPLAY INVISIBLE (-2015 4935);
FORCEPROP 1 LASTPIN (-2025 4925) BN 6
J 0
(-2037 4933);
DISPLAY 0.680851 (-2037 4933);
PAINT GREEN (-2037 4933);
FORCEPROP 2 LAST CDS_LIB standard
J 0
(-1975 4925);
DISPLAY INVISIBLE (-1975 4925);
FORCEPROP 1 LAST BODY_TYPE PLUMBING
J 0
(-1975 4975);
DISPLAY 0.872340 (-1975 4975);
PAINT GREEN (-1975 4975);
DISPLAY INVISIBLE (-1975 4975);
FORCEPROP 1 LAST HDL_TAP TRUE
J 0
(-1650 4800);
DISPLAY 0.872340 (-1650 4800);
DISPLAY INVISIBLE (-1650 4800);
FORCEPROP 1 LAST PATH I30
J 0
(-1977 4925);
DISPLAY 0.872340 (-1977 4925);
PAINT GREEN (-1977 4925);
DISPLAY INVISIBLE (-1977 4925);
FORCEADD TAP..1
(-2175 5025);
FORCEPROP 3 LASTPIN (-2225 5025) SIG_NAME P5E_CPU0_P3_TX_C_DN<6>
J 0
(-2215 5035);
DISPLAY 0.659574 (-2215 5035);
PAINT MONO (-2215 5035);
DISPLAY INVISIBLE (-2215 5035);
FORCEPROP 1 LASTPIN (-2225 5025) BN 6
J 0
(-2237 5033);
DISPLAY 0.680851 (-2237 5033);
PAINT GREEN (-2237 5033);
FORCEPROP 2 LAST CDS_LIB standard
J 0
(-2175 5025);
DISPLAY INVISIBLE (-2175 5025);
FORCEPROP 1 LAST BODY_TYPE PLUMBING
J 0
(-2175 5075);
DISPLAY 0.872340 (-2175 5075);
PAINT GREEN (-2175 5075);
DISPLAY INVISIBLE (-2175 5075);
FORCEPROP 1 LAST HDL_TAP TRUE
J 0
(-1850 4900);
DISPLAY 0.872340 (-1850 4900);
DISPLAY INVISIBLE (-1850 4900);
FORCEPROP 1 LAST PATH I31
J 0
(-2177 5025);
DISPLAY 0.872340 (-2177 5025);
PAINT GREEN (-2177 5025);
DISPLAY INVISIBLE (-2177 5025);
FORCEADD TAP..1
(-2175 5375);
FORCEPROP 3 LASTPIN (-2225 5375) SIG_NAME P5E_CPU0_P3_TX_C_DN<7>
J 0
(-2215 5385);
DISPLAY 0.659574 (-2215 5385);
PAINT MONO (-2215 5385);
DISPLAY INVISIBLE (-2215 5385);
FORCEPROP 1 LASTPIN (-2225 5375) BN 7
J 0
(-2237 5383);
DISPLAY 0.680851 (-2237 5383);
PAINT GREEN (-2237 5383);
FORCEPROP 2 LAST CDS_LIB standard
J 0
(-2175 5375);
DISPLAY INVISIBLE (-2175 5375);
FORCEPROP 1 LAST BODY_TYPE PLUMBING
J 0
(-2175 5425);
DISPLAY 0.872340 (-2175 5425);
PAINT GREEN (-2175 5425);
DISPLAY INVISIBLE (-2175 5425);
FORCEPROP 1 LAST HDL_TAP TRUE
J 0
(-1850 5250);
DISPLAY 0.872340 (-1850 5250);
DISPLAY INVISIBLE (-1850 5250);
FORCEPROP 1 LAST PATH I32
J 0
(-2177 5375);
DISPLAY 0.872340 (-2177 5375);
PAINT GREEN (-2177 5375);
DISPLAY INVISIBLE (-2177 5375);
FORCEADD TAP..1
(-1975 5275);
FORCEPROP 3 LASTPIN (-2025 5275) SIG_NAME P5E_CPU0_P3_TX_C_DP<7>
J 0
(-2015 5285);
DISPLAY 0.659574 (-2015 5285);
PAINT MONO (-2015 5285);
DISPLAY INVISIBLE (-2015 5285);
FORCEPROP 1 LASTPIN (-2025 5275) BN 7
J 0
(-2037 5283);
DISPLAY 0.680851 (-2037 5283);
PAINT GREEN (-2037 5283);
FORCEPROP 2 LAST CDS_LIB standard
J 0
(-1975 5275);
DISPLAY INVISIBLE (-1975 5275);
FORCEPROP 1 LAST BODY_TYPE PLUMBING
J 0
(-1975 5325);
DISPLAY 0.872340 (-1975 5325);
PAINT GREEN (-1975 5325);
DISPLAY INVISIBLE (-1975 5325);
FORCEPROP 1 LAST HDL_TAP TRUE
J 0
(-1650 5150);
DISPLAY 0.872340 (-1650 5150);
DISPLAY INVISIBLE (-1650 5150);
FORCEPROP 1 LAST PATH I33
J 0
(-1977 5275);
DISPLAY 0.872340 (-1977 5275);
PAINT GREEN (-1977 5275);
DISPLAY INVISIBLE (-1977 5275);
FORCEADD OFFPAGE..1
R 2
(-975 5400);
FORCEPROP 2 LAST $XR0 64 
J 0
(-789 5400);
DISPLAY 0.638298 (-789 5400);
PAINT MONO (-789 5400);
FORCEPROP 2 LAST CDS_LIB standard
J 2
(-975 5400);
DISPLAY INVISIBLE (-975 5400);
FORCEPROP 1 LAST OFFPAGE TRUE
J 2
(-1300 5275);
DISPLAY 0.872340 (-1300 5275);
DISPLAY INVISIBLE (-1300 5275);
FORCEPROP 1 LAST COMMENT_BODY TRUE
J 2
(-1100 5300);
DISPLAY 0.872340 (-1100 5300);
PAINT GREEN (-1100 5300);
DISPLAY INVISIBLE (-1100 5300);
FORCEPROP 2 LAST PATH I34
J 0
(-800 5475);
DISPLAY 0.680851 (-800 5475);
DISPLAY INVISIBLE (-800 5475);
FORCEADD OFFPAGE..1
R 2
(-975 5300);
FORCEPROP 2 LAST $XR0 64 
J 0
(-789 5300);
DISPLAY 0.638298 (-789 5300);
PAINT MONO (-789 5300);
FORCEPROP 2 LAST CDS_LIB standard
J 0
(-975 5300);
DISPLAY INVISIBLE (-975 5300);
FORCEPROP 1 LAST OFFPAGE TRUE
J 2
(-1300 5175);
DISPLAY 0.872340 (-1300 5175);
DISPLAY INVISIBLE (-1300 5175);
FORCEPROP 1 LAST COMMENT_BODY TRUE
J 2
(-1100 5200);
DISPLAY 0.872340 (-1100 5200);
PAINT GREEN (-1100 5200);
DISPLAY INVISIBLE (-1100 5200);
FORCEPROP 2 LAST PATH I35
J 0
(-800 5375);
DISPLAY 0.680851 (-800 5375);
DISPLAY INVISIBLE (-800 5375);
FORCEADD TAP..1
(-1975 2825);
FORCEPROP 3 LASTPIN (-2025 2825) SIG_NAME P5E_CPU0_P3_TX_C_DP<0>
J 0
(-2015 2835);
DISPLAY 0.659574 (-2015 2835);
PAINT MONO (-2015 2835);
DISPLAY INVISIBLE (-2015 2835);
FORCEPROP 1 LASTPIN (-2025 2825) BN 0
J 0
(-2037 2833);
DISPLAY 0.680851 (-2037 2833);
PAINT GREEN (-2037 2833);
FORCEPROP 2 LAST CDS_LIB standard
J 0
(-1975 2825);
DISPLAY INVISIBLE (-1975 2825);
FORCEPROP 1 LAST BODY_TYPE PLUMBING
J 0
(-1975 2875);
DISPLAY 0.872340 (-1975 2875);
PAINT GREEN (-1975 2875);
DISPLAY INVISIBLE (-1975 2875);
FORCEPROP 1 LAST HDL_TAP TRUE
J 0
(-1650 2700);
DISPLAY 0.872340 (-1650 2700);
DISPLAY INVISIBLE (-1650 2700);
FORCEPROP 1 LAST PATH I36
J 0
(-1977 2825);
DISPLAY 0.872340 (-1977 2825);
PAINT GREEN (-1977 2825);
DISPLAY INVISIBLE (-1977 2825);
FORCEADD TAP..1
(-2175 2925);
FORCEPROP 3 LASTPIN (-2225 2925) SIG_NAME P5E_CPU0_P3_TX_C_DN<0>
J 0
(-2215 2935);
DISPLAY 0.659574 (-2215 2935);
PAINT MONO (-2215 2935);
DISPLAY INVISIBLE (-2215 2935);
FORCEPROP 1 LASTPIN (-2225 2925) BN 0
J 0
(-2237 2933);
DISPLAY 0.680851 (-2237 2933);
PAINT GREEN (-2237 2933);
FORCEPROP 2 LAST CDS_LIB standard
J 0
(-2175 2925);
DISPLAY INVISIBLE (-2175 2925);
FORCEPROP 1 LAST BODY_TYPE PLUMBING
J 0
(-2175 2975);
DISPLAY 0.872340 (-2175 2975);
PAINT GREEN (-2175 2975);
DISPLAY INVISIBLE (-2175 2975);
FORCEPROP 1 LAST HDL_TAP TRUE
J 0
(-1850 2800);
DISPLAY 0.872340 (-1850 2800);
DISPLAY INVISIBLE (-1850 2800);
FORCEPROP 1 LAST PATH I37
J 0
(-2177 2925);
DISPLAY 0.872340 (-2177 2925);
PAINT GREEN (-2177 2925);
DISPLAY INVISIBLE (-2177 2925);
FORCEADD PT5161LRS..9
(-3200 4125);
FORCEPROP 1 LAST LOCATION U6013
J 0
(-3550 5750);
DISPLAY 0.723404 (-3550 5750);
PAINT GREEN (-3550 5750);
FORCEPROP 0 LAST $SEC 9
J 0
(-3550 5900);
DISPLAY 0.680851 (-3550 5900);
PAINT MONO (-3550 5900);
DISPLAY INVISIBLE (-3550 5900);
FORCEPROP 0 LAST CDS_SEC 9
J 0
(-3550 5900);
DISPLAY 0.680851 (-3550 5900);
DISPLAY INVISIBLE (-3550 5900);
FORCEPROP 0 LASTPIN (-2750 5275) $PN CL35
J 0
(-2740 5285);
DISPLAY 0.680851 (-2740 5285);
PAINT MONO (-2740 5285);
FORCEPROP 0 LASTPIN (-2750 4925) $PN CV35
J 0
(-2740 4935);
DISPLAY 0.680851 (-2740 4935);
PAINT MONO (-2740 4935);
FORCEPROP 0 LASTPIN (-2750 4575) $PN DE35
J 0
(-2740 4585);
DISPLAY 0.680851 (-2740 4585);
PAINT MONO (-2740 4585);
FORCEPROP 0 LASTPIN (-2750 4225) $PN DM35
J 0
(-2740 4235);
DISPLAY 0.680851 (-2740 4235);
PAINT MONO (-2740 4235);
FORCEPROP 0 LASTPIN (-2750 3875) $PN DW35
J 0
(-2740 3885);
DISPLAY 0.680851 (-2740 3885);
PAINT MONO (-2740 3885);
FORCEPROP 0 LASTPIN (-2750 3525) $PN EF35
J 0
(-2740 3535);
DISPLAY 0.680851 (-2740 3535);
PAINT MONO (-2740 3535);
FORCEPROP 0 LASTPIN (-2750 3175) $PN EN35
J 0
(-2740 3185);
DISPLAY 0.680851 (-2740 3185);
PAINT MONO (-2740 3185);
FORCEPROP 0 LASTPIN (-2750 2825) $PN EY35
J 0
(-2740 2835);
DISPLAY 0.680851 (-2740 2835);
PAINT MONO (-2740 2835);
FORCEPROP 0 LASTPIN (-2750 5375) $PN CJ34
J 0
(-2740 5385);
DISPLAY 0.680851 (-2740 5385);
PAINT MONO (-2740 5385);
FORCEPROP 0 LASTPIN (-2750 5025) $PN CT34
J 0
(-2740 5035);
DISPLAY 0.680851 (-2740 5035);
PAINT MONO (-2740 5035);
FORCEPROP 0 LASTPIN (-2750 4675) $PN DC34
J 0
(-2740 4685);
DISPLAY 0.680851 (-2740 4685);
PAINT MONO (-2740 4685);
FORCEPROP 0 LASTPIN (-2750 4325) $PN DK34
J 0
(-2740 4335);
DISPLAY 0.680851 (-2740 4335);
PAINT MONO (-2740 4335);
FORCEPROP 0 LASTPIN (-2750 3975) $PN DU34
J 0
(-2740 3985);
DISPLAY 0.680851 (-2740 3985);
PAINT MONO (-2740 3985);
FORCEPROP 0 LASTPIN (-2750 3625) $PN ED34
J 0
(-2740 3635);
DISPLAY 0.680851 (-2740 3635);
PAINT MONO (-2740 3635);
FORCEPROP 0 LASTPIN (-2750 3275) $PN EL34
J 0
(-2740 3285);
DISPLAY 0.680851 (-2740 3285);
PAINT MONO (-2740 3285);
FORCEPROP 0 LASTPIN (-2750 2925) $PN EV34
J 0
(-2740 2935);
DISPLAY 0.680851 (-2740 2935);
PAINT MONO (-2740 2935);
FORCEPROP 1 LAST MATERIAL IC
J 0
(-3550 5600);
DISPLAY 0.723404 (-3550 5600);
PAINT GREEN (-3550 5600);
FORCEPROP 2 LAST VALUE PT5161LRS
J 0
(-3550 5800);
DISPLAY 0.680851 (-3550 5800);
FORCEPROP 2 LAST PART_TYPE SMLF
J 0
(-3550 5850);
DISPLAY 0.680851 (-3550 5850);
FORCEPROP 2 LAST CDS_LIB pure_quanta
J 0
(-3200 4125);
DISPLAY INVISIBLE (-3200 4125);
FORCEPROP 1 LAST CDS_LMAN_SYM_OUTLINE -350,1450,300,-1400
J 0
(-3200 4125);
DISPLAY 0.468085 (-3200 4125);
PAINT GREEN (-3200 4125);
DISPLAY INVISIBLE (-3200 4125);
FORCEPROP 1 LAST NEEDS_NO_SIZE TRUE
J 0
(-3200 4125);
DISPLAY 0.723404 (-3200 4125);
PAINT GREEN (-3200 4125);
DISPLAY INVISIBLE (-3200 4125);
FORCEPROP 1 LAST PATH I38
J 0
(-3200 4125);
DISPLAY 0.723404 (-3200 4125);
PAINT GREEN (-3200 4125);
DISPLAY INVISIBLE (-3200 4125);
FORCEPROP 1 LAST PART_NUMBER AJ051610U03
J 0
(-3550 5675);
DISPLAY 0.723404 (-3550 5675);
PAINT GREEN (-3550 5675);
DISPLAY INVISIBLE (-3550 5675);
FORCEADD TAP..1
(-6800 3325);
FORCEPROP 3 LASTPIN (-6850 3325) SIG_NAME P5E_CPU0_P3_TX_C_DN<9>
J 0
(-6840 3335);
DISPLAY 0.659574 (-6840 3335);
PAINT MONO (-6840 3335);
DISPLAY INVISIBLE (-6840 3335);
FORCEPROP 1 LASTPIN (-6850 3325) BN 9
J 0
(-6862 3333);
DISPLAY 0.680851 (-6862 3333);
PAINT GREEN (-6862 3333);
FORCEPROP 2 LAST CDS_LIB standard
J 0
(-6800 3325);
DISPLAY INVISIBLE (-6800 3325);
FORCEPROP 1 LAST BODY_TYPE PLUMBING
J 0
(-6800 3375);
DISPLAY 0.872340 (-6800 3375);
PAINT GREEN (-6800 3375);
DISPLAY INVISIBLE (-6800 3375);
FORCEPROP 1 LAST HDL_TAP TRUE
J 0
(-6475 3200);
DISPLAY 0.872340 (-6475 3200);
DISPLAY INVISIBLE (-6475 3200);
FORCEPROP 1 LAST PATH I4
J 0
(-6802 3325);
DISPLAY 0.872340 (-6802 3325);
PAINT GREEN (-6802 3325);
DISPLAY INVISIBLE (-6802 3325);
FORCEADD TAP..1
(-6600 3225);
FORCEPROP 3 LASTPIN (-6650 3225) SIG_NAME P5E_CPU0_P3_TX_C_DP<9>
J 0
(-6640 3235);
DISPLAY 0.659574 (-6640 3235);
PAINT MONO (-6640 3235);
DISPLAY INVISIBLE (-6640 3235);
FORCEPROP 1 LASTPIN (-6650 3225) BN 9
J 0
(-6662 3233);
DISPLAY 0.680851 (-6662 3233);
PAINT GREEN (-6662 3233);
FORCEPROP 2 LAST CDS_LIB standard
J 0
(-6600 3225);
DISPLAY INVISIBLE (-6600 3225);
FORCEPROP 1 LAST BODY_TYPE PLUMBING
J 0
(-6600 3275);
DISPLAY 0.872340 (-6600 3275);
PAINT GREEN (-6600 3275);
DISPLAY INVISIBLE (-6600 3275);
FORCEPROP 1 LAST HDL_TAP TRUE
J 0
(-6275 3100);
DISPLAY 0.872340 (-6275 3100);
DISPLAY INVISIBLE (-6275 3100);
FORCEPROP 1 LAST PATH I5
J 0
(-6602 3225);
DISPLAY 0.872340 (-6602 3225);
PAINT GREEN (-6602 3225);
DISPLAY INVISIBLE (-6602 3225);
FORCEADD TAP..1
(-6800 3675);
FORCEPROP 3 LASTPIN (-6850 3675) SIG_NAME P5E_CPU0_P3_TX_C_DN<10>
J 0
(-6840 3685);
DISPLAY 0.659574 (-6840 3685);
PAINT MONO (-6840 3685);
DISPLAY INVISIBLE (-6840 3685);
FORCEPROP 1 LASTPIN (-6850 3675) BN 10
J 0
(-6862 3683);
DISPLAY 0.680851 (-6862 3683);
PAINT GREEN (-6862 3683);
FORCEPROP 2 LAST CDS_LIB standard
J 0
(-6800 3675);
DISPLAY INVISIBLE (-6800 3675);
FORCEPROP 1 LAST BODY_TYPE PLUMBING
J 0
(-6800 3725);
DISPLAY 0.872340 (-6800 3725);
PAINT GREEN (-6800 3725);
DISPLAY INVISIBLE (-6800 3725);
FORCEPROP 1 LAST HDL_TAP TRUE
J 0
(-6475 3550);
DISPLAY 0.872340 (-6475 3550);
DISPLAY INVISIBLE (-6475 3550);
FORCEPROP 1 LAST PATH I6
J 0
(-6802 3675);
DISPLAY 0.872340 (-6802 3675);
PAINT GREEN (-6802 3675);
DISPLAY INVISIBLE (-6802 3675);
FORCEADD TAP..1
(-6600 3575);
FORCEPROP 3 LASTPIN (-6650 3575) SIG_NAME P5E_CPU0_P3_TX_C_DP<10>
J 0
(-6640 3585);
DISPLAY 0.659574 (-6640 3585);
PAINT MONO (-6640 3585);
DISPLAY INVISIBLE (-6640 3585);
FORCEPROP 1 LASTPIN (-6650 3575) BN 10
J 0
(-6662 3583);
DISPLAY 0.680851 (-6662 3583);
PAINT GREEN (-6662 3583);
FORCEPROP 2 LAST CDS_LIB standard
J 0
(-6600 3575);
DISPLAY INVISIBLE (-6600 3575);
FORCEPROP 1 LAST BODY_TYPE PLUMBING
J 0
(-6600 3625);
DISPLAY 0.872340 (-6600 3625);
PAINT GREEN (-6600 3625);
DISPLAY INVISIBLE (-6600 3625);
FORCEPROP 1 LAST HDL_TAP TRUE
J 0
(-6275 3450);
DISPLAY 0.872340 (-6275 3450);
DISPLAY INVISIBLE (-6275 3450);
FORCEPROP 1 LAST PATH I7
J 0
(-6602 3575);
DISPLAY 0.872340 (-6602 3575);
PAINT GREEN (-6602 3575);
DISPLAY INVISIBLE (-6602 3575);
FORCEADD TAP..1
(-6600 3925);
FORCEPROP 3 LASTPIN (-6650 3925) SIG_NAME P5E_CPU0_P3_TX_C_DP<11>
J 0
(-6640 3935);
DISPLAY 0.659574 (-6640 3935);
PAINT MONO (-6640 3935);
DISPLAY INVISIBLE (-6640 3935);
FORCEPROP 1 LASTPIN (-6650 3925) BN 11
J 0
(-6662 3933);
DISPLAY 0.680851 (-6662 3933);
PAINT GREEN (-6662 3933);
FORCEPROP 2 LAST CDS_LIB standard
J 0
(-6600 3925);
DISPLAY INVISIBLE (-6600 3925);
FORCEPROP 1 LAST BODY_TYPE PLUMBING
J 0
(-6600 3975);
DISPLAY 0.872340 (-6600 3975);
PAINT GREEN (-6600 3975);
DISPLAY INVISIBLE (-6600 3975);
FORCEPROP 1 LAST HDL_TAP TRUE
J 0
(-6275 3800);
DISPLAY 0.872340 (-6275 3800);
DISPLAY INVISIBLE (-6275 3800);
FORCEPROP 1 LAST PATH I8
J 0
(-6602 3925);
DISPLAY 0.872340 (-6602 3925);
PAINT GREEN (-6602 3925);
DISPLAY INVISIBLE (-6602 3925);
FORCEADD TAP..1
(-6800 4025);
FORCEPROP 3 LASTPIN (-6850 4025) SIG_NAME P5E_CPU0_P3_TX_C_DN<11>
J 0
(-6840 4035);
DISPLAY 0.659574 (-6840 4035);
PAINT MONO (-6840 4035);
DISPLAY INVISIBLE (-6840 4035);
FORCEPROP 1 LASTPIN (-6850 4025) BN 11
J 0
(-6862 4033);
DISPLAY 0.680851 (-6862 4033);
PAINT GREEN (-6862 4033);
FORCEPROP 2 LAST CDS_LIB standard
J 0
(-6800 4025);
DISPLAY INVISIBLE (-6800 4025);
FORCEPROP 1 LAST BODY_TYPE PLUMBING
J 0
(-6800 4075);
DISPLAY 0.872340 (-6800 4075);
PAINT GREEN (-6800 4075);
DISPLAY INVISIBLE (-6800 4075);
FORCEPROP 1 LAST HDL_TAP TRUE
J 0
(-6475 3900);
DISPLAY 0.872340 (-6475 3900);
DISPLAY INVISIBLE (-6475 3900);
FORCEPROP 1 LAST PATH I9
J 0
(-6802 4025);
DISPLAY 0.872340 (-6802 4025);
PAINT GREEN (-6802 4025);
DISPLAY INVISIBLE (-6802 4025);
FORCEADD QUANTA_TITLE_BLOCK_C..1
(0 0);
FORCEPROP 0 LAST CDS_CON_LAST_MODIFIED Thu Sep 14 16:12:53 2023
J 0
(-1885 15);
DISPLAY INVISIBLE (-1885 15);
FORCEPROP 1 LAST CUSTOM_TXT_CDS <CON_LAST_MODIFIED>
J 0
(-1885 15);
DISPLAY 0.978723 (-1885 15);
FORCEPROP 2 LAST CUSTOM_TXT_CDS <XR_PAGE_TITLE>
J 0
(-7890 5250);
DISPLAY 0.638298 (-7890 5250);
PAINT PINK (-7890 5250);
DISPLAY INVISIBLE (-7890 5250);
FORCEPROP 1 LAST CUSTOM_TXT_CDS <NAME_2>
J 0
(-3175 50);
FORCEPROP 1 LAST CUSTOM_TXT_CDS <NAME_1>
J 0
(-3175 175);
FORCEPROP 1 LAST CUSTOM_TXT_CDS <Q_NUMBER>
J 0
(-1403 103);
DISPLAY 1.212766 (-1403 103);
FORCEPROP 1 LAST CUSTOM_TXT_CDS <Q_PROJ>
J 0
(-2382 102);
DISPLAY 1.212766 (-2382 102);
FORCEPROP 1 LAST CUSTOM_TXT_CDS <Q_REV>
J 0
(-184 103);
DISPLAY 1.212766 (-184 103);
FORCEPROP 1 LAST CUSTOM_TXT_CDS <CON_PAGE_NUM> OF <CON_TOTAL_PAGES>
J 0
(-446 18);
DISPLAY 0.978723 (-446 18);
FORCEPROP 1 LAST Q_TITLE RETIMER_CPU0_P3(1)
J 0
(-9366 26);
DISPLAY 2.446809 (-9366 26);
PAINT GREEN (-9366 26);
FORCEPROP 2 LAST CDS_LIB pure_quanta
J 0
(0 0);
DISPLAY INVISIBLE (0 0);
FORCEPROP 1 LAST CDS_LMAN_SYM_OUTLINE -9475,6775,100,-125
J 0
(0 0);
DISPLAY 0.468085 (0 0);
PAINT GREEN (0 0);
DISPLAY INVISIBLE (0 0);
FORCEPROP 2 LAST PAGE_BORDER TRUE
J 0
(-7890 5250);
DISPLAY 0.638298 (-7890 5250);
PAINT PINK (-7890 5250);
DISPLAY INVISIBLE (-7890 5250);
FORCEPROP 2 LAST CDS_XR_PAGE_TITLE CR-306 : @T6G_MB_LIB.T6G(SCH_1):PAGE306
J 0
(-7890 5250);
DISPLAY 0.638298 (-7890 5250);
PAINT PINK (-7890 5250);
DISPLAY INVISIBLE (-7890 5250);
FORCEPROP 1 LAST Q_DEPT BU9
J 1
(-3763 49);
DISPLAY 1.957447 (-3763 49);
PAINT GREEN (-3763 49);
DISPLAY INVISIBLE (-3763 49);
FORCEPROP 1 LAST COMMENT_BODY TRUE
J 0
(12 -13);
DISPLAY 0.978723 (12 -13);
PAINT GREEN (12 -13);
DISPLAY INVISIBLE (12 -13);
WIRE 17 -1 (-2125 5400)(-1025 5400);
FORCEPROP 2 LAST SIG_NAME P5E_CPU0_P3_TX_C_DN<7:0>
J 0
(-1860 5410);
DISPLAY 0.680851 (-1860 5410);
PAINT WHITE (-1860 5410);
WIRE 17 -1 (-1925 3300)(-1925 2850);
WIRE 17 -1 (-1925 3550)(-1925 3300);
WIRE 17 -1 (-1925 3900)(-1925 3550);
WIRE 17 -1 (-1925 3900)(-1925 4250);
WIRE 17 -1 (-1925 4600)(-1925 4250);
WIRE 17 -1 (-1925 4950)(-1925 4600);
WIRE 17 -1 (-1925 5300)(-1925 4950);
WIRE 17 -1 (-1925 5300)(-1025 5300);
FORCEPROP 2 LAST SIG_NAME P5E_CPU0_P3_TX_C_DP<7:0>
J 0
(-1860 5310);
DISPLAY 0.680851 (-1860 5310);
PAINT WHITE (-1860 5310);
WIRE 17 -1 (-2125 5050)(-2125 4700);
WIRE 17 -1 (-2125 5400)(-2125 5050);
WIRE 17 -1 (-2125 4700)(-2125 4350);
WIRE 17 -1 (-2125 4000)(-2125 4350);
WIRE 17 -1 (-2125 4000)(-2125 3650);
WIRE 17 -1 (-2125 3650)(-2125 3200);
WIRE 17 -1 (-2125 3200)(-2125 2950);
WIRE 17 -1 (-6750 3350)(-6750 3000);
WIRE 17 -1 (-6750 3700)(-6750 3350);
WIRE 17 -1 (-6750 4050)(-6750 3700);
WIRE 17 -1 (-6750 4050)(-6750 4400);
WIRE 17 -1 (-6750 4750)(-6750 4400);
WIRE 17 -1 (-6750 5000)(-6750 4750);
WIRE 17 -1 (-6750 5450)(-6750 5000);
WIRE 17 -1 (-6750 5450)(-5650 5450);
FORCEPROP 2 LAST SIG_NAME P5E_CPU0_P3_TX_C_DN<15:8>
J 0
(-6485 5460);
DISPLAY 0.680851 (-6485 5460);
PAINT WHITE (-6485 5460);
WIRE 17 -1 (-6550 3250)(-6550 2900);
WIRE 17 -1 (-6550 3600)(-6550 3250);
WIRE 17 -1 (-6550 3950)(-6550 3600);
WIRE 17 -1 (-6550 3950)(-6550 4300);
WIRE 17 -1 (-6550 4650)(-6550 4300);
WIRE 17 -1 (-6550 5100)(-6550 4650);
WIRE 17 -1 (-6550 5350)(-6550 5100);
WIRE 17 -1 (-6550 5350)(-5650 5350);
FORCEPROP 2 LAST SIG_NAME P5E_CPU0_P3_TX_C_DP<15:8>
J 0
(-6485 5360);
DISPLAY 0.680851 (-6485 5360);
PAINT WHITE (-6485 5360);
WIRE 16 -1 (-2750 5025)(-2225 5025);
WIRE 16 -1 (-2750 4925)(-2025 4925);
WIRE 16 -1 (-2750 4225)(-2025 4225);
WIRE 16 -1 (-2750 4325)(-2225 4325);
WIRE 16 -1 (-7375 3225)(-6650 3225);
WIRE 16 -1 (-7375 3575)(-6650 3575);
WIRE 16 -1 (-7375 3925)(-6650 3925);
WIRE 16 -1 (-7375 4625)(-6650 4625);
WIRE 16 -1 (-7375 5075)(-6650 5075);
WIRE 16 -1 (-7375 5325)(-6650 5325);
WIRE 16 -1 (-6850 4975)(-7375 4975);
WIRE 16 -1 (-7375 4275)(-6650 4275);
WIRE 16 -1 (-7375 2875)(-6650 2875);
WIRE 16 -1 (-7375 3325)(-6850 3325);
WIRE 16 -1 (-7375 3675)(-6850 3675);
WIRE 16 -1 (-7375 4025)(-6850 4025);
WIRE 16 -1 (-7375 4375)(-6850 4375);
WIRE 16 -1 (-7375 4725)(-6850 4725);
WIRE 16 -1 (-7375 5425)(-6850 5425);
WIRE 16 -1 (-7375 2975)(-6850 2975);
WIRE 16 -1 (-2750 2925)(-2225 2925);
WIRE 16 -1 (-2225 3175)(-2750 3175);
WIRE 16 -1 (-2750 3275)(-2025 3275);
WIRE 16 -1 (-2750 3525)(-2025 3525);
WIRE 16 -1 (-2750 3625)(-2225 3625);
WIRE 16 -1 (-2750 3875)(-2025 3875);
WIRE 16 -1 (-2750 3975)(-2225 3975);
WIRE 16 -1 (-2750 4575)(-2025 4575);
WIRE 16 -1 (-2750 4675)(-2225 4675);
WIRE 16 -1 (-2750 5275)(-2025 5275);
WIRE 16 -1 (-2750 2825)(-2025 2825);
WIRE 16 -1 (-2750 5375)(-2225 5375);
FORCENOTE
CPU TO RETIMER
(-3650 2025) 0;
DISPLAY LEFT (-3650 2025);
DISPLAY 3.148936 (-3650 2025);
FORCENOTE
CPU TO RETIMER
(-8250 2025) 0;
DISPLAY LEFT (-8250 2025);
DISPLAY 3.148936 (-8250 2025);
FORCENOTE
P5E_CPU0_P3_TX_C_DP/DN<0-15> LANE REVERSAL
(-9150 6175) 0;
DISPLAY LEFT (-9150 6175);
DISPLAY 2.000000 (-9150 6175);
FORCENOTE
P/N SWAP
(-6450 4675) 0;
DISPLAY LEFT (-6450 4675);
DISPLAY 1.021277 (-6450 4675);
FORCENOTE
P/N SWAP
(-6450 4325) 0;
DISPLAY LEFT (-6450 4325);
DISPLAY 1.021277 (-6450 4325);
FORCENOTE
P/N SWAP
(-6475 3925) 0;
DISPLAY LEFT (-6475 3925);
DISPLAY 1.021277 (-6475 3925);
FORCENOTE
P/N SWAP
(-6450 3600) 0;
DISPLAY LEFT (-6450 3600);
DISPLAY 1.021277 (-6450 3600);
FORCENOTE
P/N SWAP
(-6400 3225) 0;
DISPLAY LEFT (-6400 3225);
DISPLAY 1.021277 (-6400 3225);
FORCENOTE
P/N SWAP
(-6425 2875) 0;
DISPLAY LEFT (-6425 2875);
DISPLAY 1.021277 (-6425 2875);
FORCENOTE
P/N SWAP
(-1800 2900) 0;
DISPLAY LEFT (-1800 2900);
DISPLAY 1.021277 (-1800 2900);
FORCENOTE
P/N SWAP
(-1850 5225) 0;
DISPLAY LEFT (-1850 5225);
DISPLAY 1.021277 (-1850 5225);
FORCENOTE
P/N SWAP
(-6475 5275) 0;
DISPLAY LEFT (-6475 5275);
DISPLAY 1.021277 (-6475 5275);
FORCENOTE
P/N SWAP
(-1800 4950) 0;
DISPLAY LEFT (-1800 4950);
DISPLAY 1.021277 (-1800 4950);
FORCENOTE
P/N SWAP
(-1850 4600) 0;
DISPLAY LEFT (-1850 4600);
DISPLAY 1.021277 (-1850 4600);
FORCENOTE
P/N SWAP
(-1850 4275) 0;
DISPLAY LEFT (-1850 4275);
DISPLAY 1.021277 (-1850 4275);
FORCENOTE
P/N SWAP
(-1800 3575) 0;
DISPLAY LEFT (-1800 3575);
DISPLAY 1.021277 (-1800 3575);
FORCENOTE
P/N SWAP
(-1775 3900) 0;
DISPLAY LEFT (-1775 3900);
DISPLAY 1.021277 (-1775 3900);
QUIT
